#ISCELL
  pure_quanta quanta_title_block_c *
  *
#CELL
  pure_quanta pt5161lrs *
  page416_i1
#ISCELL
  standard tap *
  page416_i10
#ISCELL
  standard tap *
  page416_i11
#ISCELL
  standard tap *
  page416_i12
#ISCELL
  standard tap *
  page416_i13
#ISCELL
  standard tap *
  page416_i14
#ISCELL
  standard tap *
  page416_i15
#ISCELL
  standard tap *
  page416_i16
#ISCELL
  standard tap *
  page416_i17
#ISCELL
  standard offpage *
  page416_i18
#ISCELL
  standard offpage *
  page416_i19
#ISCELL
  standard tap *
  page416_i2
#ISCELL
  standard tap *
  page416_i20
#ISCELL
  standard tap *
  page416_i21
#ISCELL
  standard tap *
  page416_i22
#ISCELL
  standard tap *
  page416_i23
#ISCELL
  standard tap *
  page416_i24
#ISCELL
  standard tap *
  page416_i25
#ISCELL
  standard tap *
  page416_i26
#ISCELL
  standard tap *
  page416_i27
#ISCELL
  standard tap *
  page416_i28
#ISCELL
  standard tap *
  page416_i29
#ISCELL
  standard tap *
  page416_i3
#ISCELL
  standard tap *
  page416_i30
#ISCELL
  standard tap *
  page416_i31
#ISCELL
  standard tap *
  page416_i32
#ISCELL
  standard tap *
  page416_i33
#ISCELL
  standard tap *
  page416_i34
#ISCELL
  standard tap *
  page416_i35
#ISCELL
  standard offpage *
  page416_i36
#ISCELL
  standard offpage *
  page416_i37
#CELL
  pure_quanta pt5161lrs *
  page416_i38
#ISCELL
  standard tap *
  page416_i4
#ISCELL
  standard tap *
  page416_i5
#ISCELL
  standard tap *
  page416_i6
#ISCELL
  standard tap *
  page416_i7
#ISCELL
  standard tap *
  page416_i8
#ISCELL
  standard tap *
  page416_i9
